# S9S_MB_2U (Grand Teton) — schematic netlist excerpt (pin names and nets, part order shuffled) for the footprints in the layout excerpt that follows; sources: Cadence DE-HDL packaged netlist, KiCad conversion of 03242023_DA0F0TMBIJ0_F0T_Motherboard_J_brd_V01_OCP.brd

PC505_P1_6  Q_CAP  3300PF 50V 10% X7R  pkg 0402  page 287 : A = SW_P12V_PVCCIN_CPU1_FLT ; B = GND
R3291  Q_RES  4.7K 1% EMPTY  pkg 0402LF  page 166 : A = PU_TEST ; B = GND

(kicad_pcb
	(version 20260206)
	(generator "pcbnew")
	(generator_version "10.0")
	(general
		(thickness 1.6)
		(legacy_teardrops no)
	)
	(paper "A4")
	(title_block
		(title "03242023_DA0F0TMBIJ0_F0T_Motherboard_J_brd_V01_OCP.brd")
		(comment 1 "Grand Teton / footprints 3648-3649 of 6105")
	)
	(layers
		(0 "F.Cu" signal "TOP")
		(4 "In1.Cu" signal "GND")
		(6 "In2.Cu" signal "IN1")
		(8 "In3.Cu" signal "GND1")
		(10 "In4.Cu" signal "IN2")
		(12 "In5.Cu" signal "GND2")
		(14 "In6.Cu" signal "IN3")
		(16 "In7.Cu" signal "GND3")
		(18 "In8.Cu" signal "VCC")
		(20 "In9.Cu" signal "VCC1")
		(22 "In10.Cu" signal "GND4")
		(24 "In11.Cu" signal "IN4")
		(26 "In12.Cu" signal "GND5")
		(28 "In13.Cu" signal "IN5")
		(30 "In14.Cu" signal "GND6")
		(32 "In15.Cu" signal "IN6")
		(34 "In16.Cu" signal "GND7")
		(2 "B.Cu" signal "BOTTOM")
		(9 "F.Adhes" user "F.Adhesive")
		(11 "B.Adhes" user "B.Adhesive")
		(13 "F.Paste" user "Package Geometry/Pastemask Top")
		(15 "B.Paste" user "Package Geometry/Pastemask Bottom")
		(5 "F.SilkS" user "Ref Des/Silkscreen Top")
		(7 "B.SilkS" user "Ref Des/Silkscreen Bottom")
		(1 "F.Mask" user "Board Geometry/Soldermask Top")
		(3 "B.Mask" user "Board Geometry/Soldermask Bottom")
		(17 "Dwgs.User" user "User.Drawings")
		(19 "Cmts.User" user "User.Comments")
		(21 "Eco1.User" user "User.Eco1")
		(23 "Eco2.User" user "User.Eco2")
		(25 "Edge.Cuts" user "Board Geometry/Outline")
		(27 "Margin" user)
		(31 "F.CrtYd" user "Package Geometry/Place Bound Top")
		(29 "B.CrtYd" user "Package Geometry/Place Bound Bottom")
		(35 "F.Fab" user "Ref Des/Assembly Top")
		(33 "B.Fab" user "Ref Des/Assembly Bottom")
	)
	(footprint ""
		(layer "F.Cu")
		(at 21.456396 -386.484876 -90)
		(property "Reference" "R3291"
			(at 0 0 270)
			(layer "F.SilkS")
			(hide yes)
			(effects
				(font
					(size 1.27 1.27)
				)
			)
		)
		(property "Value" ""
			(at 0 0 270)
			(layer "F.Fab")
			(effects
				(font
					(size 1.27 1.27)
				)
			)
		)
		(duplicate_pad_numbers_are_jumpers no)
		(fp_line
			(start -0.7874 0.4064)
			(end -0.7874 -0.4064)
			(stroke
				(width 0.1524)
				(type default)
			)
			(layer "F.SilkS")
		)
		(fp_line
			(start 0.7874 0.4064)
			(end -0.7874 0.4064)
			(stroke
				(width 0.1524)
				(type default)
			)
			(layer "F.SilkS")
		)
		(fp_line
			(start -0.7874 -0.4064)
			(end 0.7874 -0.4064)
			(stroke
				(width 0.1524)
				(type default)
			)
			(layer "F.SilkS")
		)
		(fp_line
			(start 0.7874 -0.4064)
			(end 0.7874 0.4064)
			(stroke
				(width 0.1524)
				(type default)
			)
			(layer "F.SilkS")
		)
		(fp_line
			(start -0.67945 0.3048)
			(end -0.67945 -0.305054)
			(stroke
				(width 0.1)
				(type default)
			)
			(layer "F.Fab")
		)
		(fp_line
			(start -0.12065 0.3048)
			(end -0.67945 0.3048)
			(stroke
				(width 0.1)
				(type default)
			)
			(layer "F.Fab")
		)
		(fp_line
			(start 0.120396 0.3048)
			(end 0.120396 0.2794)
			(stroke
				(width 0.1)
				(type default)
			)
			(layer "F.Fab")
		)
		(fp_line
			(start 0.67945 0.3048)
			(end 0.120396 0.3048)
			(stroke
				(width 0.1)
				(type default)
			)
			(layer "F.Fab")
		)
		(fp_line
			(start -0.12065 0.2794)
			(end -0.12065 0.3048)
			(stroke
				(width 0.1)
				(type default)
			)
			(layer "F.Fab")
		)
		(fp_line
			(start 0.120396 0.2794)
			(end -0.12065 0.2794)
			(stroke
				(width 0.1)
				(type default)
			)
			(layer "F.Fab")
		)
		(fp_line
			(start -0.12065 -0.2794)
			(end 0.12065 -0.2794)
			(stroke
				(width 0.1)
				(type default)
			)
			(layer "F.Fab")
		)
		(fp_line
			(start 0.12065 -0.2794)
			(end 0.12065 -0.3048)
			(stroke
				(width 0.1)
				(type default)
			)
			(layer "F.Fab")
		)
		(fp_line
			(start 0.12065 -0.3048)
			(end 0.67945 -0.3048)
			(stroke
				(width 0.1)
				(type default)
			)
			(layer "F.Fab")
		)
		(fp_line
			(start 0.67945 -0.3048)
			(end 0.67945 0.3048)
			(stroke
				(width 0.1)
				(type default)
			)
			(layer "F.Fab")
		)
		(fp_line
			(start -0.67945 -0.305054)
			(end -0.12065 -0.305054)
			(stroke
				(width 0.1)
				(type default)
			)
			(layer "F.Fab")
		)
		(fp_line
			(start -0.12065 -0.305054)
			(end -0.12065 -0.2794)
			(stroke
				(width 0.1)
				(type default)
			)
			(layer "F.Fab")
		)
		(pad "1" smd circle
			(at -0.40005 0 270)
			(size 0 0)
			(layers "F.Cu" "F.Mask" "F.Paste")
			(net "PU_TEST")
		)
		(pad "2" smd circle
			(at 0.40005 0 270)
			(size 0 0)
			(layers "F.Cu" "F.Mask" "F.Paste")
			(net "GND")
		)
	)
	(footprint ""
		(layer "F.Cu")
		(at 93.193362 -339.51545 -90)
		(property "Reference" "PC505_P1_6"
			(at 0 0 270)
			(layer "F.SilkS")
			(hide yes)
			(effects
				(font
					(size 1.27 1.27)
				)
			)
		)
		(property "Value" ""
			(at 0 0 270)
			(layer "F.Fab")
			(effects
				(font
					(size 1.27 1.27)
				)
			)
		)
		(duplicate_pad_numbers_are_jumpers no)
		(fp_line
			(start -0.7874 0.4064)
			(end -0.7874 -0.4064)
			(stroke
				(width 0.1524)
				(type default)
			)
			(layer "F.SilkS")
		)
		(fp_line
			(start 0.7874 0.4064)
			(end -0.7874 0.4064)
			(stroke
				(width 0.1524)
				(type default)
			)
			(layer "F.SilkS")
		)
		(fp_line
			(start -0.7874 -0.4064)
			(end 0.7874 -0.4064)
			(stroke
				(width 0.1524)
				(type default)
			)
			(layer "F.SilkS")
		)
		(fp_line
			(start 0.7874 -0.4064)
			(end 0.7874 0.4064)
			(stroke
				(width 0.1524)
				(type default)
			)
			(layer "F.SilkS")
		)
		(fp_line
			(start -0.67945 0.3048)
			(end -0.67945 -0.305054)
			(stroke
				(width 0.1)
				(type default)
			)
			(layer "F.Fab")
		)
		(fp_line
			(start -0.12065 0.3048)
			(end -0.67945 0.3048)
			(stroke
				(width 0.1)
				(type default)
			)
			(layer "F.Fab")
		)
		(fp_line
			(start 0.120396 0.3048)
			(end 0.120396 0.2794)
			(stroke
				(width 0.1)
				(type default)
			)
			(layer "F.Fab")
		)
		(fp_line
			(start 0.67945 0.3048)
			(end 0.120396 0.3048)
			(stroke
				(width 0.1)
				(type default)
			)
			(layer "F.Fab")
		)
		(fp_line
			(start -0.12065 0.2794)
			(end -0.12065 0.3048)
			(stroke
				(width 0.1)
				(type default)
			)
			(layer "F.Fab")
		)
		(fp_line
			(start 0.120396 0.2794)
			(end -0.12065 0.2794)
			(stroke
				(width 0.1)
				(type default)
			)
			(layer "F.Fab")
		)
		(fp_line
			(start -0.12065 -0.2794)
			(end 0.12065 -0.2794)
			(stroke
				(width 0.1)
				(type default)
			)
			(layer "F.Fab")
		)
		(fp_line
			(start 0.12065 -0.2794)
			(end 0.12065 -0.3048)
			(stroke
				(width 0.1)
				(type default)
			)
			(layer "F.Fab")
		)
		(fp_line
			(start 0.12065 -0.3048)
			(end 0.67945 -0.3048)
			(stroke
				(width 0.1)
				(type default)
			)
			(layer "F.Fab")
		)
		(fp_line
			(start 0.67945 -0.3048)
			(end 0.67945 0.3048)
			(stroke
				(width 0.1)
				(type default)
			)
			(layer "F.Fab")
		)
		(fp_line
			(start -0.67945 -0.305054)
			(end -0.12065 -0.305054)
			(stroke
				(width 0.1)
				(type default)
			)
			(layer "F.Fab")
		)
		(fp_line
			(start -0.12065 -0.305054)
			(end -0.12065 -0.2794)
			(stroke
				(width 0.1)
				(type default)
			)
			(layer "F.Fab")
		)
		(pad "1" smd circle
			(at -0.40005 0 270)
			(size 0 0)
			(layers "F.Cu" "F.Mask" "F.Paste")
			(net "SW_P12V_PVCCIN_CPU1_FLT")
		)
		(pad "2" smd circle
			(at 0.40005 0 270)
			(size 0 0)
			(layers "F.Cu" "F.Mask" "F.Paste")
			(net "GND")
		)
	)
)
